(kicad_pcb
	(version 20241229)
	(generator "pcbnew")
	(generator_version "9.0")
	(general
		(thickness 1.62)
		(legacy_teardrops no)
	)
	(paper "A4")
	(title_block
		(title "OCuLink to 10GbE adapter")
		(date "2026-02-23")
		(rev "1.1.0")
		(company "Antmicro Ltd")
		(comment 1 "www.antmicro.com")
		(comment 9 "footprints 408-412 of 510")
	)
	(layers
		(0 "F.Cu" signal)
		(4 "In1.Cu" signal)
		(6 "In2.Cu" signal)
		(8 "In3.Cu" signal)
		(10 "In4.Cu" signal)
		(12 "In5.Cu" signal)
		(14 "In6.Cu" signal)
		(2 "B.Cu" signal)
		(9 "F.Adhes" user "F.Adhesive")
		(11 "B.Adhes" user "B.Adhesive")
		(13 "F.Paste" user)
		(15 "B.Paste" user)
		(5 "F.SilkS" user "F.Silkscreen")
		(7 "B.SilkS" user "B.Silkscreen")
		(1 "F.Mask" user)
		(3 "B.Mask" user)
		(17 "Dwgs.User" user "User.Drawings")
		(19 "Cmts.User" user "User.Comments")
		(21 "Eco1.User" user "User.Eco1")
		(23 "Eco2.User" user "User.Eco2")
		(25 "Edge.Cuts" user)
		(27 "Margin" user)
		(31 "F.CrtYd" user "F.Courtyard")
		(29 "B.CrtYd" user "B.Courtyard")
		(35 "F.Fab" user)
		(33 "B.Fab" user)
	)
	(footprint "antmicro-footprints:R_0402_1005Metric"
		(layer "B.Cu")
		(at 102.08 89.214 180)
		(descr "Resistor SMD 0402")
		(tags "resistor SMD 0402")
		(property "Reference" "R124"
			(at -1.87 -2.736 0)
			(layer "B.SilkS")
			(effects
				(font
					(size 0.7 0.7)
					(thickness 0.15)
				)
				(justify left bottom mirror)
			)
		)
		(property "Value" "R_33R_0402"
			(at -1.011843 -1.772047 0)
			(layer "B.Fab")
			(hide yes)
			(effects
				(font
					(size 0.7 0.7)
					(thickness 0.15)
				)
				(justify left bottom mirror)
			)
		)
		(property "Datasheet" "https://www.bourns.com/docs/product-datasheets/cr.pdf"
			(at 0 0 0)
			(layer "B.Fab")
			(hide yes)
			(effects
				(font
					(size 1.27 1.27)
					(thickness 0.15)
				)
				(justify mirror)
			)
		)
		(property "Description" "SMD Chip Resistor, 33 ohm, ± 1%, 62.5 mW, 0402 [1005 Metric], Thick Film, General Purpose"
			(at 0 0 0)
			(layer "B.Fab")
			(hide yes)
			(effects
				(font
					(size 1.27 1.27)
					(thickness 0.15)
				)
				(justify mirror)
			)
		)
		(property "MPN" "CR0402-FX-33R0GLF"
			(at 0 0 0)
			(unlocked yes)
			(layer "B.Fab")
			(hide yes)
			(effects
				(font
					(size 1 1)
					(thickness 0.15)
				)
				(justify mirror)
			)
		)
		(property "Manufacturer" "Bourns"
			(at 0 0 0)
			(unlocked yes)
			(layer "B.Fab")
			(hide yes)
			(effects
				(font
					(size 1 1)
					(thickness 0.15)
				)
				(justify mirror)
			)
		)
		(property "License" "Apache-2.0"
			(at 0 0 0)
			(unlocked yes)
			(layer "B.Fab")
			(hide yes)
			(effects
				(font
					(size 1 1)
					(thickness 0.15)
				)
				(justify mirror)
			)
		)
		(property "Author" "Antmicro"
			(at 0 0 0)
			(unlocked yes)
			(layer "B.Fab")
			(hide yes)
			(effects
				(font
					(size 1 1)
					(thickness 0.15)
				)
				(justify mirror)
			)
		)
		(property "Val" "33R"
			(at 0 0 0)
			(unlocked yes)
			(layer "B.Fab")
			(hide yes)
			(effects
				(font
					(size 1 1)
					(thickness 0.15)
				)
				(justify mirror)
			)
		)
		(property "Tolerance" "1%"
			(at 0 0 0)
			(unlocked yes)
			(layer "B.Fab")
			(hide yes)
			(effects
				(font
					(size 1 1)
					(thickness 0.15)
				)
				(justify mirror)
			)
		)
		(sheetname "/X710-AT2 PCIe/")
		(sheetfile "x710-at2-pcie.kicad_sch")
		(attr smd exclude_from_pos_files exclude_from_bom dnp)
		(fp_rect
			(start -0.925 0.47)
			(end 0.925 -0.47)
			(stroke
				(width 0.05)
				(type default)
			)
			(fill no)
			(layer "B.CrtYd")
		)
		(fp_rect
			(start -0.5 0.25)
			(end 0.5 -0.25)
			(stroke
				(width 0.15)
				(type solid)
			)
			(fill no)
			(layer "B.Fab")
		)
		(pad "1" smd roundrect
			(at -0.48 0 180)
			(size 0.59 0.64)
			(layers "B.Cu" "B.Mask" "B.Paste")
			(roundrect_rratio 0.25)
			(net 408 "/X710-AT2 PCIe/GEN_CLK-")
			(pintype "passive")
		)
		(pad "2" smd roundrect
			(at 0.48 0 180)
			(size 0.59 0.64)
			(layers "B.Cu" "B.Mask" "B.Paste")
			(roundrect_rratio 0.25)
			(net 406 "/X710-AT2 PCIe/GEN_F_CLK-")
			(pintype "passive")
		)
	)
	(footprint "antmicro-footprints:SOT-416"
		(layer "B.Cu")
		(at 56.25 118.05)
		(descr "SOT-416")
		(tags "SOT-416")
		(property "Reference" "Q9"
			(at 1.169999 0.8 270)
			(layer "B.SilkS")
			(effects
				(font
					(size 0.7 0.7)
					(thickness 0.15)
				)
				(justify right top mirror)
			)
		)
		(property "Value" "DTC014T_SOT-416"
			(at 0 -2.000001 0)
			(layer "B.Fab")
			(hide yes)
			(effects
				(font
					(size 0.7 0.7)
					(thickness 0.15)
				)
				(justify right top mirror)
			)
		)
		(property "Datasheet" "https://www.rohm.com/datasheet?p=DTC014TEB&dist=Mouser&media=referral&source=mouser.com&campaign=Mouser"
			(at 0 0 0)
			(layer "B.Fab")
			(hide yes)
			(effects
				(font
					(size 1.27 1.27)
					(thickness 0.15)
				)
				(justify mirror)
			)
		)
		(property "Description" "Bipolar (BJT) Single Transistor with built-in base resistor, NPN, 50V, 100mA, 150mW, SOT-416FL, Surface Mount"
			(at 0 0 0)
			(layer "B.Fab")
			(hide yes)
			(effects
				(font
					(size 1.27 1.27)
					(thickness 0.15)
				)
				(justify mirror)
			)
		)
		(property "Manufacturer" "ROHM Semiconductor"
			(at 0 0 180)
			(unlocked yes)
			(layer "B.Fab")
			(hide yes)
			(effects
				(font
					(size 1 1)
					(thickness 0.15)
				)
				(justify mirror)
			)
		)
		(property "MPN" "DTC014TEBTL"
			(at 0 0 180)
			(unlocked yes)
			(layer "B.Fab")
			(hide yes)
			(effects
				(font
					(size 1 1)
					(thickness 0.15)
				)
				(justify mirror)
			)
		)
		(property "Author" "Antmicro"
			(at 0 0 180)
			(unlocked yes)
			(layer "B.Fab")
			(hide yes)
			(effects
				(font
					(size 1 1)
					(thickness 0.15)
				)
				(justify mirror)
			)
		)
		(property "License" "Apache-2.0"
			(at 0 0 180)
			(unlocked yes)
			(layer "B.Fab")
			(hide yes)
			(effects
				(font
					(size 1 1)
					(thickness 0.15)
				)
				(justify mirror)
			)
		)
		(sheetname "/Power/")
		(sheetfile "power.kicad_sch")
		(attr smd)
		(fp_line
			(start -0.5 0.15)
			(end -0.5 -0.15)
			(stroke
				(width 0.15)
				(type solid)
			)
			(layer "B.SilkS")
		)
		(fp_line
			(start 0.5 -0.9)
			(end -0.5 -0.9)
			(stroke
				(width 0.15)
				(type solid)
			)
			(layer "B.SilkS")
		)
		(fp_line
			(start 0.5 -0.9)
			(end 0.5 -0.7)
			(stroke
				(width 0.15)
				(type solid)
			)
			(layer "B.SilkS")
		)
		(fp_line
			(start 0.508 0.9)
			(end -0.5 0.9)
			(stroke
				(width 0.15)
				(type solid)
			)
			(layer "B.SilkS")
		)
		(fp_line
			(start 0.508 0.9)
			(end 0.508 0.592)
			(stroke
				(width 0.15)
				(type solid)
			)
			(layer "B.SilkS")
		)
		(fp_rect
			(start -1 1.05)
			(end 1 -1.05)
			(stroke
				(width 0.05)
				(type solid)
			)
			(fill no)
			(layer "B.CrtYd")
		)
		(fp_line
			(start -0.05 0.9)
			(end -0.45 0.5)
			(stroke
				(width 0.15)
				(type solid)
			)
			(layer "B.Fab")
		)
		(fp_rect
			(start 0.45 -0.9)
			(end -0.45 0.9)
			(stroke
				(width 0.15)
				(type solid)
			)
			(fill no)
			(layer "B.Fab")
		)
		(fp_text user "License: Apache-2.0"
			(at -1 -5.802 180)
			(layer "B.Fab")
			(effects
				(font
					(size 0.7 0.7)
					(thickness 0.15)
				)
				(justify left bottom mirror)
			)
		)
		(fp_text user "${REFERENCE}"
			(at -1 -3.4 180)
			(layer "B.Fab")
			(effects
				(font
					(size 0.7 0.7)
					(thickness 0.15)
				)
				(justify left bottom mirror)
			)
		)
		(fp_text user "Author: Antmicro"
			(at -1 -4.602 180)
			(layer "B.Fab")
			(effects
				(font
					(size 0.7 0.7)
					(thickness 0.15)
				)
				(justify left bottom mirror)
			)
		)
		(pad "1" smd rect
			(at -0.652 0.5)
			(size 0.6 0.5)
			(layers "B.Cu" "B.Mask" "B.Paste")
			(net 311 "/Power/+DVDD_OUT")
			(pinfunction "B")
			(pintype "input")
		)
		(pad "2" smd rect
			(at -0.652 -0.498)
			(size 0.6 0.5)
			(layers "B.Cu" "B.Mask" "B.Paste")
			(net 28 "GND")
			(pinfunction "E")
			(pintype "passive")
		)
		(pad "3" smd rect
			(at 0.65 0)
			(size 0.6 0.5)
			(layers "B.Cu" "B.Mask" "B.Paste")
			(net 419 "Net-(Q9-C)")
			(pinfunction "C")
			(pintype "passive")
		)
	)
	(footprint "antmicro-footprints:R_0402_1005Metric"
		(layer "B.Cu")
		(at 73.75 88.9 -90)
		(descr "Resistor SMD 0402")
		(tags "resistor SMD 0402")
		(property "Reference" "R34"
			(at -1.1 -0.6 90)
			(layer "B.SilkS")
			(effects
				(font
					(size 0.7 0.7)
					(thickness 0.15)
				)
				(justify left top mirror)
			)
		)
		(property "Value" "R_10k_0402"
			(at -1.011843 -1.772046 90)
			(layer "B.Fab")
			(hide yes)
			(effects
				(font
					(size 0.7 0.7)
					(thickness 0.15)
				)
				(justify left bottom mirror)
			)
		)
		(property "Datasheet" "https://www.bourns.com/docs/product-datasheets/cr.pdf"
			(at 0 0 90)
			(layer "B.Fab")
			(hide yes)
			(effects
				(font
					(size 1.27 1.27)
					(thickness 0.15)
				)
				(justify mirror)
			)
		)
		(property "Description" "SMD Chip Resistor, 10 kohm, ± 1%, 62.5 mW, 0402 [1005 Metric], Thick Film, General Purpose"
			(at 0 0 90)
			(layer "B.Fab")
			(hide yes)
			(effects
				(font
					(size 1.27 1.27)
					(thickness 0.15)
				)
				(justify mirror)
			)
		)
		(property "MPN" "CR0402-FX-1002GLF"
			(at 0 0 270)
			(unlocked yes)
			(layer "B.Fab")
			(hide yes)
			(effects
				(font
					(size 1 1)
					(thickness 0.15)
				)
				(justify mirror)
			)
		)
		(property "Manufacturer" "Bourns"
			(at 0 0 270)
			(unlocked yes)
			(layer "B.Fab")
			(hide yes)
			(effects
				(font
					(size 1 1)
					(thickness 0.15)
				)
				(justify mirror)
			)
		)
		(property "License" "Apache-2.0"
			(at 0 0 270)
			(unlocked yes)
			(layer "B.Fab")
			(hide yes)
			(effects
				(font
					(size 1 1)
					(thickness 0.15)
				)
				(justify mirror)
			)
		)
		(property "Author" "Antmicro"
			(at 0 0 270)
			(unlocked yes)
			(layer "B.Fab")
			(hide yes)
			(effects
				(font
					(size 1 1)
					(thickness 0.15)
				)
				(justify mirror)
			)
		)
		(property "Val" "10k"
			(at 0 0 270)
			(unlocked yes)
			(layer "B.Fab")
			(hide yes)
			(effects
				(font
					(size 1 1)
					(thickness 0.15)
				)
				(justify mirror)
			)
		)
		(property "Tolerance" "1%"
			(at 0 0 270)
			(unlocked yes)
			(layer "B.Fab")
			(hide yes)
			(effects
				(font
					(size 1 1)
					(thickness 0.15)
				)
				(justify mirror)
			)
		)
		(sheetname "/Flash memory/")
		(sheetfile "flash-memory.kicad_sch")
		(attr smd)
		(fp_rect
			(start -0.925 0.47)
			(end 0.925 -0.47)
			(stroke
				(width 0.05)
				(type default)
			)
			(fill no)
			(layer "B.CrtYd")
		)
		(fp_rect
			(start -0.5 0.25)
			(end 0.5 -0.25)
			(stroke
				(width 0.15)
				(type solid)
			)
			(fill no)
			(layer "B.Fab")
		)
		(pad "1" smd roundrect
			(at -0.48 0 270)
			(size 0.59 0.64)
			(layers "B.Cu" "B.Mask" "B.Paste")
			(roundrect_rratio 0.25)
			(net 71 "/Flash memory/~{HOLD}")
			(pintype "passive")
		)
		(pad "2" smd roundrect
			(at 0.48 0 270)
			(size 0.59 0.64)
			(layers "B.Cu" "B.Mask" "B.Paste")
			(roundrect_rratio 0.25)
			(net 110 "/Flash memory/+3V3_FLASH")
			(pintype "passive")
		)
	)
	(footprint "antmicro-footprints:C_0402_1005Metric"
		(layer "B.Cu")
		(at 103.95 131.4 180)
		(descr "Capacitor SMD 0402")
		(tags "capacitor SMD 0402")
		(property "Reference" "C67"
			(at -2.99 -0.45 0)
			(layer "B.SilkS")
			(effects
				(font
					(size 0.7 0.7)
					(thickness 0.15)
				)
				(justify left bottom mirror)
			)
		)
		(property "Value" "C_1u_25V_0402"
			(at -1.022927 -2.155213 0)
			(layer "B.Fab")
			(hide yes)
			(effects
				(font
					(size 0.7 0.7)
					(thickness 0.15)
				)
				(justify left bottom mirror)
			)
		)
		(property "Datasheet" "https://www.murata.com/products/productdetail?partno=GRM155R61E105KE11%23"
			(at 0 0 0)
			(layer "B.Fab")
			(hide yes)
			(effects
				(font
					(size 1.27 1.27)
					(thickness 0.15)
				)
				(justify mirror)
			)
		)
		(property "Description" "SMD Multilayer Ceramic Capacitor, 1 µF, 25 V, 0402 [1005 Metric], ± 10%, X5R, GRM Series"
			(at 0 0 0)
			(layer "B.Fab")
			(hide yes)
			(effects
				(font
					(size 1.27 1.27)
					(thickness 0.15)
				)
				(justify mirror)
			)
		)
		(property "MPN" "GRM155R61E105KE11J"
			(at 0 0 180)
			(unlocked yes)
			(layer "B.Fab")
			(hide yes)
			(effects
				(font
					(size 1 1)
					(thickness 0.15)
				)
				(justify mirror)
			)
		)
		(property "Manufacturer" "Murata"
			(at 0 0 180)
			(unlocked yes)
			(layer "B.Fab")
			(hide yes)
			(effects
				(font
					(size 1 1)
					(thickness 0.15)
				)
				(justify mirror)
			)
		)
		(property "License" "Apache-2.0"
			(at 0 0 180)
			(unlocked yes)
			(layer "B.Fab")
			(hide yes)
			(effects
				(font
					(size 1 1)
					(thickness 0.15)
				)
				(justify mirror)
			)
		)
		(property "Author" "Antmicro"
			(at 0 0 180)
			(unlocked yes)
			(layer "B.Fab")
			(hide yes)
			(effects
				(font
					(size 1 1)
					(thickness 0.15)
				)
				(justify mirror)
			)
		)
		(property "Val" "1u"
			(at 0 0 180)
			(unlocked yes)
			(layer "B.Fab")
			(hide yes)
			(effects
				(font
					(size 1 1)
					(thickness 0.15)
				)
				(justify mirror)
			)
		)
		(property "Voltage" "25V"
			(at 0 0 180)
			(unlocked yes)
			(layer "B.Fab")
			(hide yes)
			(effects
				(font
					(size 1 1)
					(thickness 0.15)
				)
				(justify mirror)
			)
		)
		(property "Dielectric" "X5R"
			(at 0 0 180)
			(unlocked yes)
			(layer "B.Fab")
			(hide yes)
			(effects
				(font
					(size 1 1)
					(thickness 0.15)
				)
				(justify mirror)
			)
		)
		(sheetname "/2xRJ45/")
		(sheetfile "2xrj45.kicad_sch")
		(attr smd)
		(fp_rect
			(start -0.925 0.47)
			(end 0.925 -0.47)
			(stroke
				(width 0.05)
				(type default)
			)
			(fill no)
			(layer "B.CrtYd")
		)
		(fp_line
			(start 0.504 0.25)
			(end 0.504 -0.248)
			(stroke
				(width 0.15)
				(type solid)
			)
			(layer "B.Fab")
		)
		(fp_line
			(start 0.504 -0.248)
			(end -0.494 -0.248)
			(stroke
				(width 0.15)
				(type solid)
			)
			(layer "B.Fab")
		)
		(fp_line
			(start -0.494 0.25)
			(end 0.504 0.25)
			(stroke
				(width 0.15)
				(type solid)
			)
			(layer "B.Fab")
		)
		(fp_line
			(start -0.494 -0.248)
			(end -0.494 0.25)
			(stroke
				(width 0.15)
				(type solid)
			)
			(layer "B.Fab")
		)
		(pad "1" smd roundrect
			(at -0.48 0 180)
			(size 0.59 0.64)
			(layers "B.Cu" "B.Mask" "B.Paste")
			(roundrect_rratio 0.25)
			(net 28 "GND")
			(pintype "passive")
		)
		(pad "2" smd roundrect
			(at 0.48 0 180)
			(size 0.59 0.64)
			(layers "B.Cu" "B.Mask" "B.Paste")
			(roundrect_rratio 0.25)
			(net 300 "/2xRJ45/P1_CT")
			(pintype "passive")
		)
	)
	(footprint "antmicro-footprints:C_0402_1005Metric"
		(layer "B.Cu")
		(at 90.225 94.6 90)
		(descr "Capacitor SMD 0402")
		(tags "capacitor SMD 0402")
		(property "Reference" "C133"
			(at 12.5 -0.462343 90)
			(layer "B.SilkS")
			(effects
				(font
					(size 0.7 0.7)
					(thickness 0.15)
				)
				(justify right top mirror)
			)
		)
		(property "Value" "C_1u_25V_0402"
			(at -1.022927 -2.155213 90)
			(layer "B.Fab")
			(hide yes)
			(effects
				(font
					(size 0.7 0.7)
					(thickness 0.15)
				)
				(justify right top mirror)
			)
		)
		(property "Datasheet" "https://www.murata.com/products/productdetail?partno=GRM155R61E105KE11%23"
			(at 0 0 90)
			(layer "B.Fab")
			(hide yes)
			(effects
				(font
					(size 1.27 1.27)
					(thickness 0.15)
				)
				(justify mirror)
			)
		)
		(property "Description" "SMD Multilayer Ceramic Capacitor, 1 µF, 25 V, 0402 [1005 Metric], ± 10%, X5R, GRM Series"
			(at 0 0 90)
			(layer "B.Fab")
			(hide yes)
			(effects
				(font
					(size 1.27 1.27)
					(thickness 0.15)
				)
				(justify mirror)
			)
		)
		(property "MPN" "GRM155R61E105KE11J"
			(at 0 0 90)
			(unlocked yes)
			(layer "B.Fab")
			(hide yes)
			(effects
				(font
					(size 1 1)
					(thickness 0.15)
				)
				(justify mirror)
			)
		)
		(property "Manufacturer" "Murata"
			(at 0 0 90)
			(unlocked yes)
			(layer "B.Fab")
			(hide yes)
			(effects
				(font
					(size 1 1)
					(thickness 0.15)
				)
				(justify mirror)
			)
		)
		(property "License" "Apache-2.0"
			(at 0 0 90)
			(unlocked yes)
			(layer "B.Fab")
			(hide yes)
			(effects
				(font
					(size 1 1)
					(thickness 0.15)
				)
				(justify mirror)
			)
		)
		(property "Author" "Antmicro"
			(at 0 0 90)
			(unlocked yes)
			(layer "B.Fab")
			(hide yes)
			(effects
				(font
					(size 1 1)
					(thickness 0.15)
				)
				(justify mirror)
			)
		)
		(property "Val" "1u"
			(at 0 0 90)
			(unlocked yes)
			(layer "B.Fab")
			(hide yes)
			(effects
				(font
					(size 1 1)
					(thickness 0.15)
				)
				(justify mirror)
			)
		)
		(property "Voltage" "25V"
			(at 0 0 90)
			(unlocked yes)
			(layer "B.Fab")
			(hide yes)
			(effects
				(font
					(size 1 1)
					(thickness 0.15)
				)
				(justify mirror)
			)
		)
		(property "Dielectric" "X5R"
			(at 0 0 90)
			(unlocked yes)
			(layer "B.Fab")
			(hide yes)
			(effects
				(font
					(size 1 1)
					(thickness 0.15)
				)
				(justify mirror)
			)
		)
		(sheetname "/X710-AT2 power/")
		(sheetfile "x710-at2-power.kicad_sch")
		(attr smd)
		(fp_rect
			(start -0.925 0.47)
			(end 0.925 -0.47)
			(stroke
				(width 0.05)
				(type default)
			)
			(fill no)
			(layer "B.CrtYd")
		)
		(fp_line
			(start 0.504 -0.248)
			(end -0.494 -0.248)
			(stroke
				(width 0.15)
				(type solid)
			)
			(layer "B.Fab")
		)
		(fp_line
			(start -0.494 -0.248)
			(end -0.494 0.25)
			(stroke
				(width 0.15)
				(type solid)
			)
			(layer "B.Fab")
		)
		(fp_line
			(start 0.504 0.25)
			(end 0.504 -0.248)
			(stroke
				(width 0.15)
				(type solid)
			)
			(layer "B.Fab")
		)
		(fp_line
			(start -0.494 0.25)
			(end 0.504 0.25)
			(stroke
				(width 0.15)
				(type solid)
			)
			(layer "B.Fab")
		)
		(pad "1" smd roundrect
			(at -0.48 0 90)
			(size 0.59 0.64)
			(layers "B.Cu" "B.Mask" "B.Paste")
			(roundrect_rratio 0.25)
			(net 28 "GND")
			(pintype "passive")
		)
		(pad "2" smd roundrect
			(at 0.48 0 90)
			(size 0.59 0.64)
			(layers "B.Cu" "B.Mask" "B.Paste")
			(roundrect_rratio 0.25)
			(net 7 "+3V3")
			(pintype "passive")
		)
	)
)
